# S9S_MB_2U (Grand Teton) — schematic netlist excerpt (pin names and nets, part order shuffled) for the footprints in the layout excerpt that follows; sources: Cadence DE-HDL packaged netlist, KiCad conversion of 03242023_DA0F0TMBIJ0_F0T_Motherboard_J_brd_V01_OCP.brd

C456  Q_CAP  47UF 4V 20% X6S  pkg C0805  page 79 : A = PVCCFA_EHV_CPU1 ; B = GND
C2333  Q_CAP  0.1UF 25V 10% X7R  pkg 0402  page 211 : A = P3V3_9ZXL045_VDD ; B = GND
C3276  Q_CAP  1000PF 50V 5% EMPTY  pkg 0402  page 274 : A = PWRGD_PVCCFA_EHV_CPU0_R ; B = GND

(kicad_pcb
	(version 20260206)
	(generator "pcbnew")
	(generator_version "10.0")
	(general
		(thickness 1.6)
		(legacy_teardrops no)
	)
	(paper "A4")
	(title_block
		(title "03242023_DA0F0TMBIJ0_F0T_Motherboard_J_brd_V01_OCP.brd")
		(comment 1 "Grand Teton / footprints 4701-4703 of 6105")
	)
	(layers
		(0 "F.Cu" signal "TOP")
		(4 "In1.Cu" signal "GND")
		(6 "In2.Cu" signal "IN1")
		(8 "In3.Cu" signal "GND1")
		(10 "In4.Cu" signal "IN2")
		(12 "In5.Cu" signal "GND2")
		(14 "In6.Cu" signal "IN3")
		(16 "In7.Cu" signal "GND3")
		(18 "In8.Cu" signal "VCC")
		(20 "In9.Cu" signal "VCC1")
		(22 "In10.Cu" signal "GND4")
		(24 "In11.Cu" signal "IN4")
		(26 "In12.Cu" signal "GND5")
		(28 "In13.Cu" signal "IN5")
		(30 "In14.Cu" signal "GND6")
		(32 "In15.Cu" signal "IN6")
		(34 "In16.Cu" signal "GND7")
		(2 "B.Cu" signal "BOTTOM")
		(9 "F.Adhes" user "F.Adhesive")
		(11 "B.Adhes" user "B.Adhesive")
		(13 "F.Paste" user "Package Geometry/Pastemask Top")
		(15 "B.Paste" user "Package Geometry/Pastemask Bottom")
		(5 "F.SilkS" user "Ref Des/Silkscreen Top")
		(7 "B.SilkS" user "Ref Des/Silkscreen Bottom")
		(1 "F.Mask" user "Board Geometry/Soldermask Top")
		(3 "B.Mask" user "Board Geometry/Soldermask Bottom")
		(17 "Dwgs.User" user "User.Drawings")
		(19 "Cmts.User" user "User.Comments")
		(21 "Eco1.User" user "User.Eco1")
		(23 "Eco2.User" user "User.Eco2")
		(25 "Edge.Cuts" user "Board Geometry/Outline")
		(27 "Margin" user)
		(31 "F.CrtYd" user "Package Geometry/Place Bound Top")
		(29 "B.CrtYd" user "Package Geometry/Place Bound Bottom")
		(35 "F.Fab" user "Ref Des/Assembly Top")
		(33 "B.Fab" user "Ref Des/Assembly Bottom")
	)
	(footprint ""
		(layer "B.Cu")
		(at 104.463088 -210.194144)
		(property "Reference" "C456"
			(at 0 0 0)
			(layer "B.SilkS")
			(hide yes)
			(effects
				(font
					(size 1.27 1.27)
				)
				(justify mirror)
			)
		)
		(property "Value" ""
			(at 0 0 0)
			(layer "B.Fab")
			(effects
				(font
					(size 1.27 1.27)
				)
				(justify mirror)
			)
		)
		(duplicate_pad_numbers_are_jumpers no)
		(fp_line
			(start -1.524 -0.762)
			(end -1.524 0.762)
			(stroke
				(width 0.1524)
				(type default)
			)
			(layer "B.SilkS")
		)
		(fp_line
			(start -1.524 0.762)
			(end 1.524 0.762)
			(stroke
				(width 0.1524)
				(type default)
			)
			(layer "B.SilkS")
		)
		(fp_line
			(start 1.524 -0.762)
			(end -1.524 -0.762)
			(stroke
				(width 0.1524)
				(type default)
			)
			(layer "B.SilkS")
		)
		(fp_line
			(start 1.524 0.762)
			(end 1.524 -0.762)
			(stroke
				(width 0.1524)
				(type default)
			)
			(layer "B.SilkS")
		)
		(fp_line
			(start -1.1049 -0.724916)
			(end 1.1049 -0.724916)
			(stroke
				(width 0.1)
				(type default)
			)
			(layer "B.Fab")
		)
		(fp_line
			(start -1.1049 0.724916)
			(end -1.1049 -0.724916)
			(stroke
				(width 0.1)
				(type default)
			)
			(layer "B.Fab")
		)
		(fp_line
			(start 1.1049 -0.724916)
			(end 1.1049 0.724916)
			(stroke
				(width 0.1)
				(type default)
			)
			(layer "B.Fab")
		)
		(fp_line
			(start 1.1049 0.724916)
			(end -1.1049 0.724916)
			(stroke
				(width 0.1)
				(type default)
			)
			(layer "B.Fab")
		)
		(pad "1" smd rect
			(at 0.889 0)
			(size 1.016 1.27)
			(layers "B.Cu" "B.Mask" "B.Paste")
			(net "PVCCFA_EHV_CPU1")
		)
		(pad "2" smd rect
			(at -0.889 0)
			(size 1.016 1.27)
			(layers "B.Cu" "B.Mask" "B.Paste")
			(net "GND")
		)
	)
	(footprint ""
		(layer "B.Cu")
		(at 111.83112 -416.048698 90)
		(property "Reference" "C2333"
			(at 0 0 90)
			(layer "B.SilkS")
			(hide yes)
			(effects
				(font
					(size 1.27 1.27)
				)
				(justify mirror)
			)
		)
		(property "Value" ""
			(at 0 0 90)
			(layer "B.Fab")
			(effects
				(font
					(size 1.27 1.27)
				)
				(justify mirror)
			)
		)
		(duplicate_pad_numbers_are_jumpers no)
		(fp_line
			(start 0.7874 -0.4064)
			(end -0.7874 -0.4064)
			(stroke
				(width 0.1524)
				(type default)
			)
			(layer "B.SilkS")
		)
		(fp_line
			(start -0.7874 -0.4064)
			(end -0.7874 0.4064)
			(stroke
				(width 0.1524)
				(type default)
			)
			(layer "B.SilkS")
		)
		(fp_line
			(start 0.7874 0.4064)
			(end 0.7874 -0.4064)
			(stroke
				(width 0.1524)
				(type default)
			)
			(layer "B.SilkS")
		)
		(fp_line
			(start -0.7874 0.4064)
			(end 0.7874 0.4064)
			(stroke
				(width 0.1524)
				(type default)
			)
			(layer "B.SilkS")
		)
		(fp_line
			(start 0.67945 -0.305054)
			(end 0.12065 -0.305054)
			(stroke
				(width 0.1)
				(type default)
			)
			(layer "B.Fab")
		)
		(fp_line
			(start 0.12065 -0.305054)
			(end 0.12065 -0.2794)
			(stroke
				(width 0.1)
				(type default)
			)
			(layer "B.Fab")
		)
		(fp_line
			(start -0.12065 -0.3048)
			(end -0.67945 -0.3048)
			(stroke
				(width 0.1)
				(type default)
			)
			(layer "B.Fab")
		)
		(fp_line
			(start -0.67945 -0.3048)
			(end -0.67945 0.3048)
			(stroke
				(width 0.1)
				(type default)
			)
			(layer "B.Fab")
		)
		(fp_line
			(start 0.12065 -0.2794)
			(end -0.12065 -0.2794)
			(stroke
				(width 0.1)
				(type default)
			)
			(layer "B.Fab")
		)
		(fp_line
			(start -0.12065 -0.2794)
			(end -0.12065 -0.3048)
			(stroke
				(width 0.1)
				(type default)
			)
			(layer "B.Fab")
		)
		(fp_line
			(start 0.12065 0.2794)
			(end 0.12065 0.3048)
			(stroke
				(width 0.1)
				(type default)
			)
			(layer "B.Fab")
		)
		(fp_line
			(start -0.120396 0.2794)
			(end 0.12065 0.2794)
			(stroke
				(width 0.1)
				(type default)
			)
			(layer "B.Fab")
		)
		(fp_line
			(start 0.67945 0.3048)
			(end 0.67945 -0.305054)
			(stroke
				(width 0.1)
				(type default)
			)
			(layer "B.Fab")
		)
		(fp_line
			(start 0.12065 0.3048)
			(end 0.67945 0.3048)
			(stroke
				(width 0.1)
				(type default)
			)
			(layer "B.Fab")
		)
		(fp_line
			(start -0.120396 0.3048)
			(end -0.120396 0.2794)
			(stroke
				(width 0.1)
				(type default)
			)
			(layer "B.Fab")
		)
		(fp_line
			(start -0.67945 0.3048)
			(end -0.120396 0.3048)
			(stroke
				(width 0.1)
				(type default)
			)
			(layer "B.Fab")
		)
		(pad "1" smd circle
			(at 0.40005 0 270)
			(size 0 0)
			(layers "B.Cu" "B.Mask" "B.Paste")
			(net "P3V3_9ZXL045_VDD")
		)
		(pad "2" smd circle
			(at -0.40005 0 270)
			(size 0 0)
			(layers "B.Cu" "B.Mask" "B.Paste")
			(net "GND")
		)
	)
	(footprint ""
		(layer "B.Cu")
		(at 430.600104 -136.526778 180)
		(property "Reference" "C3276"
			(at 0 0 0)
			(layer "B.SilkS")
			(hide yes)
			(effects
				(font
					(size 1.27 1.27)
				)
				(justify mirror)
			)
		)
		(property "Value" ""
			(at 0 0 0)
			(layer "B.Fab")
			(effects
				(font
					(size 1.27 1.27)
				)
				(justify mirror)
			)
		)
		(duplicate_pad_numbers_are_jumpers no)
		(fp_line
			(start 0.7874 0.4064)
			(end 0.7874 -0.4064)
			(stroke
				(width 0.1524)
				(type default)
			)
			(layer "B.SilkS")
		)
		(fp_line
			(start 0.7874 -0.4064)
			(end -0.7874 -0.4064)
			(stroke
				(width 0.1524)
				(type default)
			)
			(layer "B.SilkS")
		)
		(fp_line
			(start -0.7874 0.4064)
			(end 0.7874 0.4064)
			(stroke
				(width 0.1524)
				(type default)
			)
			(layer "B.SilkS")
		)
		(fp_line
			(start -0.7874 -0.4064)
			(end -0.7874 0.4064)
			(stroke
				(width 0.1524)
				(type default)
			)
			(layer "B.SilkS")
		)
		(fp_line
			(start 0.67945 0.3048)
			(end 0.67945 -0.305054)
			(stroke
				(width 0.1)
				(type default)
			)
			(layer "B.Fab")
		)
		(fp_line
			(start 0.67945 -0.305054)
			(end 0.12065 -0.305054)
			(stroke
				(width 0.1)
				(type default)
			)
			(layer "B.Fab")
		)
		(fp_line
			(start 0.12065 0.3048)
			(end 0.67945 0.3048)
			(stroke
				(width 0.1)
				(type default)
			)
			(layer "B.Fab")
		)
		(fp_line
			(start 0.12065 0.2794)
			(end 0.12065 0.3048)
			(stroke
				(width 0.1)
				(type default)
			)
			(layer "B.Fab")
		)
		(fp_line
			(start 0.12065 -0.2794)
			(end -0.12065 -0.2794)
			(stroke
				(width 0.1)
				(type default)
			)
			(layer "B.Fab")
		)
		(fp_line
			(start 0.12065 -0.305054)
			(end 0.12065 -0.2794)
			(stroke
				(width 0.1)
				(type default)
			)
			(layer "B.Fab")
		)
		(fp_line
			(start -0.120396 0.3048)
			(end -0.120396 0.2794)
			(stroke
				(width 0.1)
				(type default)
			)
			(layer "B.Fab")
		)
		(fp_line
			(start -0.120396 0.2794)
			(end 0.12065 0.2794)
			(stroke
				(width 0.1)
				(type default)
			)
			(layer "B.Fab")
		)
		(fp_line
			(start -0.12065 -0.2794)
			(end -0.12065 -0.3048)
			(stroke
				(width 0.1)
				(type default)
			)
			(layer "B.Fab")
		)
		(fp_line
			(start -0.12065 -0.3048)
			(end -0.67945 -0.3048)
			(stroke
				(width 0.1)
				(type default)
			)
			(layer "B.Fab")
		)
		(fp_line
			(start -0.67945 0.3048)
			(end -0.120396 0.3048)
			(stroke
				(width 0.1)
				(type default)
			)
			(layer "B.Fab")
		)
		(fp_line
			(start -0.67945 -0.3048)
			(end -0.67945 0.3048)
			(stroke
				(width 0.1)
				(type default)
			)
			(layer "B.Fab")
		)
		(pad "1" smd circle
			(at 0.40005 0)
			(size 0 0)
			(layers "B.Cu" "B.Mask" "B.Paste")
			(net "PWRGD_PVCCFA_EHV_CPU0_R")
		)
		(pad "2" smd circle
			(at -0.40005 0)
			(size 0 0)
			(layers "B.Cu" "B.Mask" "B.Paste")
			(net "GND")
		)
	)
)
